# S9S_MB_2U (Grand Teton) — schematic netlist excerpt (pin names and nets, part order shuffled) for the footprints in the layout excerpt that follows; sources: Cadence DE-HDL packaged netlist, KiCad conversion of 03242023_DA0F0TMBIJ0_F0T_Motherboard_J_brd_V01_OCP.brd

R4790  Q_RES  4.75K 1% EMPTY  pkg 0402LF  page 307 : A = P12V_AUX ; B = PWRGD_DSW_PWROK_TRIGGER
R4622  Q_RES  2K 1% CHIP  pkg 0402LF  page 219 : A = RST_PERST_SWB_N ; B = GND

(kicad_pcb
	(version 20260206)
	(generator "pcbnew")
	(generator_version "10.0")
	(general
		(thickness 1.6)
		(legacy_teardrops no)
	)
	(paper "A4")
	(title_block
		(title "03242023_DA0F0TMBIJ0_F0T_Motherboard_J_brd_V01_OCP.brd")
		(comment 1 "Grand Teton / footprints 1758-1759 of 6105")
	)
	(layers
		(0 "F.Cu" signal "TOP")
		(4 "In1.Cu" signal "GND")
		(6 "In2.Cu" signal "IN1")
		(8 "In3.Cu" signal "GND1")
		(10 "In4.Cu" signal "IN2")
		(12 "In5.Cu" signal "GND2")
		(14 "In6.Cu" signal "IN3")
		(16 "In7.Cu" signal "GND3")
		(18 "In8.Cu" signal "VCC")
		(20 "In9.Cu" signal "VCC1")
		(22 "In10.Cu" signal "GND4")
		(24 "In11.Cu" signal "IN4")
		(26 "In12.Cu" signal "GND5")
		(28 "In13.Cu" signal "IN5")
		(30 "In14.Cu" signal "GND6")
		(32 "In15.Cu" signal "IN6")
		(34 "In16.Cu" signal "GND7")
		(2 "B.Cu" signal "BOTTOM")
		(9 "F.Adhes" user "F.Adhesive")
		(11 "B.Adhes" user "B.Adhesive")
		(13 "F.Paste" user "Package Geometry/Pastemask Top")
		(15 "B.Paste" user "Package Geometry/Pastemask Bottom")
		(5 "F.SilkS" user "Ref Des/Silkscreen Top")
		(7 "B.SilkS" user "Ref Des/Silkscreen Bottom")
		(1 "F.Mask" user "Board Geometry/Soldermask Top")
		(3 "B.Mask" user "Board Geometry/Soldermask Bottom")
		(17 "Dwgs.User" user "User.Drawings")
		(19 "Cmts.User" user "User.Comments")
		(21 "Eco1.User" user "User.Eco1")
		(23 "Eco2.User" user "User.Eco2")
		(25 "Edge.Cuts" user "Board Geometry/Outline")
		(27 "Margin" user)
		(31 "F.CrtYd" user "Package Geometry/Place Bound Top")
		(29 "B.CrtYd" user "Package Geometry/Place Bound Bottom")
		(35 "F.Fab" user "Ref Des/Assembly Top")
		(33 "B.Fab" user "Ref Des/Assembly Bottom")
	)
	(footprint ""
		(layer "F.Cu")
		(at 22.91842 -428.401988)
		(property "Reference" "R4622"
			(at 0 0 0)
			(layer "F.SilkS")
			(hide yes)
			(effects
				(font
					(size 1.27 1.27)
				)
			)
		)
		(property "Value" ""
			(at 0 0 0)
			(layer "F.Fab")
			(effects
				(font
					(size 1.27 1.27)
				)
			)
		)
		(duplicate_pad_numbers_are_jumpers no)
		(fp_line
			(start -0.7874 -0.4064)
			(end 0.7874 -0.4064)
			(stroke
				(width 0.1524)
				(type default)
			)
			(layer "F.SilkS")
		)
		(fp_line
			(start -0.7874 0.4064)
			(end -0.7874 -0.4064)
			(stroke
				(width 0.1524)
				(type default)
			)
			(layer "F.SilkS")
		)
		(fp_line
			(start 0.7874 -0.4064)
			(end 0.7874 0.4064)
			(stroke
				(width 0.1524)
				(type default)
			)
			(layer "F.SilkS")
		)
		(fp_line
			(start 0.7874 0.4064)
			(end -0.7874 0.4064)
			(stroke
				(width 0.1524)
				(type default)
			)
			(layer "F.SilkS")
		)
		(fp_line
			(start -0.67945 -0.305054)
			(end -0.12065 -0.305054)
			(stroke
				(width 0.1)
				(type default)
			)
			(layer "F.Fab")
		)
		(fp_line
			(start -0.67945 0.3048)
			(end -0.67945 -0.305054)
			(stroke
				(width 0.1)
				(type default)
			)
			(layer "F.Fab")
		)
		(fp_line
			(start -0.12065 -0.305054)
			(end -0.12065 -0.2794)
			(stroke
				(width 0.1)
				(type default)
			)
			(layer "F.Fab")
		)
		(fp_line
			(start -0.12065 -0.2794)
			(end 0.12065 -0.2794)
			(stroke
				(width 0.1)
				(type default)
			)
			(layer "F.Fab")
		)
		(fp_line
			(start -0.12065 0.2794)
			(end -0.12065 0.3048)
			(stroke
				(width 0.1)
				(type default)
			)
			(layer "F.Fab")
		)
		(fp_line
			(start -0.12065 0.3048)
			(end -0.67945 0.3048)
			(stroke
				(width 0.1)
				(type default)
			)
			(layer "F.Fab")
		)
		(fp_line
			(start 0.120396 0.2794)
			(end -0.12065 0.2794)
			(stroke
				(width 0.1)
				(type default)
			)
			(layer "F.Fab")
		)
		(fp_line
			(start 0.120396 0.3048)
			(end 0.120396 0.2794)
			(stroke
				(width 0.1)
				(type default)
			)
			(layer "F.Fab")
		)
		(fp_line
			(start 0.12065 -0.3048)
			(end 0.67945 -0.3048)
			(stroke
				(width 0.1)
				(type default)
			)
			(layer "F.Fab")
		)
		(fp_line
			(start 0.12065 -0.2794)
			(end 0.12065 -0.3048)
			(stroke
				(width 0.1)
				(type default)
			)
			(layer "F.Fab")
		)
		(fp_line
			(start 0.67945 -0.3048)
			(end 0.67945 0.3048)
			(stroke
				(width 0.1)
				(type default)
			)
			(layer "F.Fab")
		)
		(fp_line
			(start 0.67945 0.3048)
			(end 0.120396 0.3048)
			(stroke
				(width 0.1)
				(type default)
			)
			(layer "F.Fab")
		)
		(pad "1" smd circle
			(at -0.40005 0)
			(size 0 0)
			(layers "F.Cu" "F.Mask" "F.Paste")
			(net "RST_PERST_SWB_N")
		)
		(pad "2" smd circle
			(at 0.40005 0)
			(size 0 0)
			(layers "F.Cu" "F.Mask" "F.Paste")
			(net "GND")
		)
	)
	(footprint ""
		(layer "F.Cu")
		(at 303.9872 -23.6728)
		(property "Reference" "R4790"
			(at 0 0 0)
			(layer "F.SilkS")
			(hide yes)
			(effects
				(font
					(size 1.27 1.27)
				)
			)
		)
		(property "Value" ""
			(at 0 0 0)
			(layer "F.Fab")
			(effects
				(font
					(size 1.27 1.27)
				)
			)
		)
		(duplicate_pad_numbers_are_jumpers no)
		(fp_line
			(start -0.7874 -0.4064)
			(end 0.7874 -0.4064)
			(stroke
				(width 0.1524)
				(type default)
			)
			(layer "F.SilkS")
		)
		(fp_line
			(start -0.7874 0.4064)
			(end -0.7874 -0.4064)
			(stroke
				(width 0.1524)
				(type default)
			)
			(layer "F.SilkS")
		)
		(fp_line
			(start 0.7874 -0.4064)
			(end 0.7874 0.4064)
			(stroke
				(width 0.1524)
				(type default)
			)
			(layer "F.SilkS")
		)
		(fp_line
			(start 0.7874 0.4064)
			(end -0.7874 0.4064)
			(stroke
				(width 0.1524)
				(type default)
			)
			(layer "F.SilkS")
		)
		(fp_line
			(start -0.67945 -0.305054)
			(end -0.12065 -0.305054)
			(stroke
				(width 0.1)
				(type default)
			)
			(layer "F.Fab")
		)
		(fp_line
			(start -0.67945 0.3048)
			(end -0.67945 -0.305054)
			(stroke
				(width 0.1)
				(type default)
			)
			(layer "F.Fab")
		)
		(fp_line
			(start -0.12065 -0.305054)
			(end -0.12065 -0.2794)
			(stroke
				(width 0.1)
				(type default)
			)
			(layer "F.Fab")
		)
		(fp_line
			(start -0.12065 -0.2794)
			(end 0.12065 -0.2794)
			(stroke
				(width 0.1)
				(type default)
			)
			(layer "F.Fab")
		)
		(fp_line
			(start -0.12065 0.2794)
			(end -0.12065 0.3048)
			(stroke
				(width 0.1)
				(type default)
			)
			(layer "F.Fab")
		)
		(fp_line
			(start -0.12065 0.3048)
			(end -0.67945 0.3048)
			(stroke
				(width 0.1)
				(type default)
			)
			(layer "F.Fab")
		)
		(fp_line
			(start 0.120396 0.2794)
			(end -0.12065 0.2794)
			(stroke
				(width 0.1)
				(type default)
			)
			(layer "F.Fab")
		)
		(fp_line
			(start 0.120396 0.3048)
			(end 0.120396 0.2794)
			(stroke
				(width 0.1)
				(type default)
			)
			(layer "F.Fab")
		)
		(fp_line
			(start 0.12065 -0.3048)
			(end 0.67945 -0.3048)
			(stroke
				(width 0.1)
				(type default)
			)
			(layer "F.Fab")
		)
		(fp_line
			(start 0.12065 -0.2794)
			(end 0.12065 -0.3048)
			(stroke
				(width 0.1)
				(type default)
			)
			(layer "F.Fab")
		)
		(fp_line
			(start 0.67945 -0.3048)
			(end 0.67945 0.3048)
			(stroke
				(width 0.1)
				(type default)
			)
			(layer "F.Fab")
		)
		(fp_line
			(start 0.67945 0.3048)
			(end 0.120396 0.3048)
			(stroke
				(width 0.1)
				(type default)
			)
			(layer "F.Fab")
		)
		(pad "1" smd circle
			(at -0.40005 0)
			(size 0 0)
			(layers "F.Cu" "F.Mask" "F.Paste")
			(net "P12V_AUX")
		)
		(pad "2" smd circle
			(at 0.40005 0)
			(size 0 0)
			(layers "F.Cu" "F.Mask" "F.Paste")
			(net "PWRGD_DSW_PWROK_TRIGGER")
		)
	)
)
